(kicad_pcb
	(version 20241229)
	(generator "pcbnew")
	(generator_version "9.0")
	(general
		(thickness 1.6296)
		(legacy_teardrops no)
	)
	(paper "A3")
	(title_block
		(title "Thunderbolt to 10GbE adapter")
		(date "2026-04-21")
		(rev "1.1.0")
		(company "Antmicro Ltd")
		(comment 1 "www.antmicro.com")
		(comment 9 "footprints 13-17 of 703")
	)
	(layers
		(0 "F.Cu" signal)
		(4 "In1.Cu" signal)
		(6 "In2.Cu" signal)
		(8 "In3.Cu" signal)
		(10 "In4.Cu" signal)
		(12 "In5.Cu" signal)
		(14 "In6.Cu" signal)
		(2 "B.Cu" signal)
		(9 "F.Adhes" user "F.Adhesive")
		(11 "B.Adhes" user "B.Adhesive")
		(13 "F.Paste" user)
		(15 "B.Paste" user)
		(5 "F.SilkS" user "F.Silkscreen")
		(7 "B.SilkS" user "B.Silkscreen")
		(1 "F.Mask" user)
		(3 "B.Mask" user)
		(17 "Dwgs.User" user "User.Drawings")
		(19 "Cmts.User" user "User.Comments")
		(21 "Eco1.User" user "User.Eco1")
		(23 "Eco2.User" user "User.Eco2")
		(25 "Edge.Cuts" user)
		(27 "Margin" user)
		(31 "F.CrtYd" user "F.Courtyard")
		(29 "B.CrtYd" user "B.Courtyard")
		(35 "F.Fab" user)
		(33 "B.Fab" user)
	)
	(footprint "antmicro-footprints:C_0402_1005Metric"
		(layer "F.Cu")
		(at 141.1 109.850002 90)
		(descr "Capacitor SMD 0402")
		(tags "capacitor SMD 0402")
		(property "Reference" "C125"
			(at -17.049998 16 90)
			(layer "F.SilkS")
			(effects
				(font
					(size 0.7 0.7)
					(thickness 0.15)
				)
			)
		)
		(property "Value" "C_100n_0402"
			(at -1.022927 2.155213 90)
			(layer "F.Fab")
			(effects
				(font
					(size 0.7 0.7)
					(thickness 0.15)
				)
				(justify left bottom)
			)
		)
		(property "Datasheet" "https://www.murata.com/products/productdetail?partno=GRM155R61H104KE14%23"
			(at 0 0 90)
			(layer "F.Fab")
			(hide yes)
			(effects
				(font
					(size 1.27 1.27)
					(thickness 0.15)
				)
			)
		)
		(property "Description" "SMD Multilayer Ceramic Capacitor, 0.1 µF, 50 V, 0402 [1005 Metric], ± 10%, X5R, GRM Series"
			(at 0 0 90)
			(layer "F.Fab")
			(hide yes)
			(effects
				(font
					(size 1.27 1.27)
					(thickness 0.15)
				)
			)
		)
		(property "MPN" "GRM155R61H104KE14D"
			(at 0 0 90)
			(unlocked yes)
			(layer "F.Fab")
			(hide yes)
			(effects
				(font
					(size 1 1)
					(thickness 0.15)
				)
			)
		)
		(property "Manufacturer" "Murata"
			(at 0 0 90)
			(unlocked yes)
			(layer "F.Fab")
			(hide yes)
			(effects
				(font
					(size 1 1)
					(thickness 0.15)
				)
			)
		)
		(property "License" "Apache-2.0"
			(at 0 0 90)
			(unlocked yes)
			(layer "F.Fab")
			(hide yes)
			(effects
				(font
					(size 1 1)
					(thickness 0.15)
				)
			)
		)
		(property "Author" "Antmicro"
			(at 0 0 90)
			(unlocked yes)
			(layer "F.Fab")
			(hide yes)
			(effects
				(font
					(size 1 1)
					(thickness 0.15)
				)
			)
		)
		(property "Val" "100n"
			(at 0 0 90)
			(unlocked yes)
			(layer "F.Fab")
			(hide yes)
			(effects
				(font
					(size 1 1)
					(thickness 0.15)
				)
			)
		)
		(property "Voltage" "50V"
			(at 0 0 90)
			(unlocked yes)
			(layer "F.Fab")
			(hide yes)
			(effects
				(font
					(size 1 1)
					(thickness 0.15)
				)
			)
		)
		(property "Dielectric" "X5R"
			(at 0 0 90)
			(unlocked yes)
			(layer "F.Fab")
			(hide yes)
			(effects
				(font
					(size 1 1)
					(thickness 0.15)
				)
			)
		)
		(sheetname "/X710 DCDC converters/")
		(sheetfile "DCDC_converters_X710.kicad_sch")
		(attr smd)
		(fp_rect
			(start -0.925 -0.47)
			(end 0.925 0.47)
			(stroke
				(width 0.05)
				(type default)
			)
			(fill no)
			(layer "F.CrtYd")
		)
		(fp_line
			(start 0.504 -0.25)
			(end 0.504 0.248)
			(stroke
				(width 0.15)
				(type solid)
			)
			(layer "F.Fab")
		)
		(fp_line
			(start -0.494 -0.25)
			(end 0.504 -0.25)
			(stroke
				(width 0.15)
				(type solid)
			)
			(layer "F.Fab")
		)
		(fp_line
			(start 0.504 0.248)
			(end -0.494 0.248)
			(stroke
				(width 0.15)
				(type solid)
			)
			(layer "F.Fab")
		)
		(fp_line
			(start -0.494 0.248)
			(end -0.494 -0.25)
			(stroke
				(width 0.15)
				(type solid)
			)
			(layer "F.Fab")
		)
		(fp_text user "License: Apache-2.0"
			(at -0.939 5.799 90)
			(layer "F.Fab")
			(effects
				(font
					(size 0.7 0.7)
					(thickness 0.15)
				)
				(justify left bottom)
			)
		)
		(fp_text user "${REFERENCE}"
			(at -0.939 4.599 90)
			(layer "F.Fab")
			(effects
				(font
					(size 0.7 0.7)
					(thickness 0.15)
				)
				(justify left bottom)
			)
		)
		(fp_text user "Author: Antmicro"
			(at -0.939 3.399 90)
			(layer "F.Fab")
			(effects
				(font
					(size 0.7 0.7)
					(thickness 0.15)
				)
				(justify left bottom)
			)
		)
		(pad "1" smd roundrect
			(at -0.48 0 90)
			(size 0.59 0.64)
			(layers "F.Cu" "F.Mask" "F.Paste")
			(roundrect_rratio 0.25)
			(net 119 "/X710 DCDC converters/VCCD_BST")
			(pintype "passive")
		)
		(pad "2" smd roundrect
			(at 0.48 0 90)
			(size 0.59 0.64)
			(layers "F.Cu" "F.Mask" "F.Paste")
			(roundrect_rratio 0.25)
			(net 153 "/X710 DCDC converters/VCCD_SW")
			(pintype "passive")
		)
	)
	(footprint "antmicro-footprints:C_0603_1608Metric"
		(layer "F.Cu")
		(at 122.15 103.3)
		(descr "Capacitor SMD 0603")
		(tags "capacitor 0603")
		(property "Reference" "C24"
			(at 2.35 -0.3 0)
			(layer "F.SilkS")
			(effects
				(font
					(size 0.7 0.7)
					(thickness 0.15)
				)
			)
		)
		(property "Value" "C_22u_0603"
			(at -1.42757 1.770288 0)
			(layer "F.Fab")
			(effects
				(font
					(size 0.7 0.7)
					(thickness 0.15)
				)
				(justify left bottom)
			)
		)
		(property "Datasheet" "https://www.murata.com/products/productdetail?partno=GRM188R60J226MEA0%23"
			(at 0 0 0)
			(layer "F.Fab")
			(hide yes)
			(effects
				(font
					(size 1.27 1.27)
					(thickness 0.15)
				)
			)
		)
		(property "Description" "SMD Multilayer Ceramic Capacitor, 22 µF, 6.3 V, 0603 [1608 Metric], ± 20%, X5R, GRM Series"
			(at 0 0 0)
			(layer "F.Fab")
			(hide yes)
			(effects
				(font
					(size 1.27 1.27)
					(thickness 0.15)
				)
			)
		)
		(property "MPN" "GRM188R60J226MEA0D"
			(at 0 0 0)
			(unlocked yes)
			(layer "F.Fab")
			(hide yes)
			(effects
				(font
					(size 1 1)
					(thickness 0.15)
				)
			)
		)
		(property "Manufacturer" "Murata"
			(at 0 0 0)
			(unlocked yes)
			(layer "F.Fab")
			(hide yes)
			(effects
				(font
					(size 1 1)
					(thickness 0.15)
				)
			)
		)
		(property "License" "Apache-2.0"
			(at 0 0 0)
			(unlocked yes)
			(layer "F.Fab")
			(hide yes)
			(effects
				(font
					(size 1 1)
					(thickness 0.15)
				)
			)
		)
		(property "Val" "22u"
			(at 0 0 0)
			(unlocked yes)
			(layer "F.Fab")
			(hide yes)
			(effects
				(font
					(size 1 1)
					(thickness 0.15)
				)
			)
		)
		(property "Voltage" ""
			(at 0 0 0)
			(unlocked yes)
			(layer "F.Fab")
			(hide yes)
			(effects
				(font
					(size 1 1)
					(thickness 0.15)
				)
			)
		)
		(property "Dielectric" ""
			(at 0 0 0)
			(unlocked yes)
			(layer "F.Fab")
			(hide yes)
			(effects
				(font
					(size 1 1)
					(thickness 0.15)
				)
			)
		)
		(property "Author" "Antmicro"
			(at 0 0 0)
			(unlocked yes)
			(layer "F.Fab")
			(hide yes)
			(effects
				(font
					(size 1 1)
					(thickness 0.15)
				)
			)
		)
		(sheetname "/PD and TB DC-DC/")
		(sheetfile "PD_and_TB_DC_DC.kicad_sch")
		(attr smd)
		(fp_line
			(start -0.15 -0.4)
			(end 0.15 -0.4)
			(stroke
				(width 0.15)
				(type solid)
			)
			(layer "F.SilkS")
		)
		(fp_line
			(start -0.15 0.4)
			(end 0.15 0.4)
			(stroke
				(width 0.15)
				(type solid)
			)
			(layer "F.SilkS")
		)
		(fp_rect
			(start -1.25 -0.65)
			(end 1.25 0.65)
			(stroke
				(width 0.05)
				(type solid)
			)
			(fill no)
			(layer "F.CrtYd")
		)
		(fp_rect
			(start -0.8 -0.4)
			(end 0.8 0.4)
			(stroke
				(width 0.15)
				(type solid)
			)
			(fill no)
			(layer "F.Fab")
		)
		(fp_text user "${REFERENCE}"
			(at -1.682 3.895 0)
			(layer "F.Fab")
			(effects
				(font
					(size 0.7 0.7)
					(thickness 0.15)
				)
				(justify left bottom)
			)
		)
		(fp_text user "License: Apache-2.0"
			(at -1.682 5.895 0)
			(layer "F.Fab")
			(effects
				(font
					(size 0.7 0.7)
					(thickness 0.15)
				)
				(justify left bottom)
			)
		)
		(fp_text user "Author: Antmicro"
			(at -1.682 4.894 0)
			(layer "F.Fab")
			(effects
				(font
					(size 0.7 0.7)
					(thickness 0.15)
				)
				(justify left bottom)
			)
		)
		(pad "1" smd roundrect
			(at -0.7 0)
			(size 0.8 1)
			(layers "F.Cu" "F.Mask" "F.Paste")
			(roundrect_rratio 0.2)
			(net 23 "GND")
			(pintype "passive")
		)
		(pad "2" smd roundrect
			(at 0.7 0)
			(size 0.8 1)
			(layers "F.Cu" "F.Mask" "F.Paste")
			(roundrect_rratio 0.2)
			(net 399 "Net-(D4-A)")
			(pintype "passive")
		)
	)
	(footprint "antmicro-footprints:C_0402_1005Metric"
		(layer "F.Cu")
		(at 129.52 92.2)
		(descr "Capacitor SMD 0402")
		(tags "capacitor SMD 0402")
		(property "Reference" "C129"
			(at 38.914999 -9.199999 0)
			(layer "F.SilkS")
			(effects
				(font
					(size 0.7 0.7)
					(thickness 0.15)
				)
			)
		)
		(property "Value" "C_33p_0402"
			(at -1.022927 2.155213 0)
			(layer "F.Fab")
			(effects
				(font
					(size 0.7 0.7)
					(thickness 0.15)
				)
				(justify left bottom)
			)
		)
		(property "Datasheet" "https://spicat.kyocera-avx.com/product/mlcc/chartview/04025A330FAT2A/"
			(at 0 0 0)
			(layer "F.Fab")
			(hide yes)
			(effects
				(font
					(size 1.27 1.27)
					(thickness 0.15)
				)
			)
		)
		(property "Description" "SMD Multilayer Ceramic Capacitor, 33 pF, 50 V, 0402 [1005 Metric], ± 5%, C0G / NP0, MC"
			(at 0 0 0)
			(layer "F.Fab")
			(hide yes)
			(effects
				(font
					(size 1.27 1.27)
					(thickness 0.15)
				)
			)
		)
		(property "MPN" "04025A330FAT2A"
			(at 0 0 0)
			(unlocked yes)
			(layer "F.Fab")
			(hide yes)
			(effects
				(font
					(size 1 1)
					(thickness 0.15)
				)
			)
		)
		(property "Manufacturer" "KYOCERA AVX"
			(at 0 0 0)
			(unlocked yes)
			(layer "F.Fab")
			(hide yes)
			(effects
				(font
					(size 1 1)
					(thickness 0.15)
				)
			)
		)
		(property "License" "Apache-2.0"
			(at 0 0 0)
			(unlocked yes)
			(layer "F.Fab")
			(hide yes)
			(effects
				(font
					(size 1 1)
					(thickness 0.15)
				)
			)
		)
		(property "Author" "Antmicro"
			(at 0 0 0)
			(unlocked yes)
			(layer "F.Fab")
			(hide yes)
			(effects
				(font
					(size 1 1)
					(thickness 0.15)
				)
			)
		)
		(property "Val" "33p"
			(at 0 0 0)
			(unlocked yes)
			(layer "F.Fab")
			(hide yes)
			(effects
				(font
					(size 1 1)
					(thickness 0.15)
				)
			)
		)
		(property "Voltage" ""
			(at 0 0 0)
			(unlocked yes)
			(layer "F.Fab")
			(hide yes)
			(effects
				(font
					(size 1 1)
					(thickness 0.15)
				)
			)
		)
		(property "Dielectric" ""
			(at 0 0 0)
			(unlocked yes)
			(layer "F.Fab")
			(hide yes)
			(effects
				(font
					(size 1 1)
					(thickness 0.15)
				)
			)
		)
		(sheetname "/X710 DCDC converters/")
		(sheetfile "DCDC_converters_X710.kicad_sch")
		(attr smd)
		(fp_rect
			(start -0.925 -0.47)
			(end 0.925 0.47)
			(stroke
				(width 0.05)
				(type default)
			)
			(fill no)
			(layer "F.CrtYd")
		)
		(fp_line
			(start -0.494 -0.25)
			(end 0.504 -0.25)
			(stroke
				(width 0.15)
				(type solid)
			)
			(layer "F.Fab")
		)
		(fp_line
			(start -0.494 0.248)
			(end -0.494 -0.25)
			(stroke
				(width 0.15)
				(type solid)
			)
			(layer "F.Fab")
		)
		(fp_line
			(start 0.504 -0.25)
			(end 0.504 0.248)
			(stroke
				(width 0.15)
				(type solid)
			)
			(layer "F.Fab")
		)
		(fp_line
			(start 0.504 0.248)
			(end -0.494 0.248)
			(stroke
				(width 0.15)
				(type solid)
			)
			(layer "F.Fab")
		)
		(fp_text user "License: Apache-2.0"
			(at -0.939 5.799 0)
			(layer "F.Fab")
			(effects
				(font
					(size 0.7 0.7)
					(thickness 0.15)
				)
				(justify left bottom)
			)
		)
		(fp_text user "Author: Antmicro"
			(at -0.939 3.399 0)
			(layer "F.Fab")
			(effects
				(font
					(size 0.7 0.7)
					(thickness 0.15)
				)
				(justify left bottom)
			)
		)
		(fp_text user "${REFERENCE}"
			(at -0.939 4.599 0)
			(layer "F.Fab")
			(effects
				(font
					(size 0.7 0.7)
					(thickness 0.15)
				)
				(justify left bottom)
			)
		)
		(pad "1" smd roundrect
			(at -0.48 0)
			(size 0.59 0.64)
			(layers "F.Cu" "F.Mask" "F.Paste")
			(roundrect_rratio 0.25)
			(net 333 "/X710 DCDC converters/3V3_FB")
			(pintype "passive")
		)
		(pad "2" smd roundrect
			(at 0.48 0)
			(size 0.59 0.64)
			(layers "F.Cu" "F.Mask" "F.Paste")
			(roundrect_rratio 0.25)
			(net 334 "/X710 DCDC converters/+3V3_OUT")
			(pintype "passive")
		)
	)
	(footprint "antmicro-footprints:R_0402_1005Metric"
		(layer "F.Cu")
		(at 135 145.5)
		(descr "Resistor SMD 0402")
		(tags "resistor SMD 0402")
		(property "Reference" "R97"
			(at 1 0.5 0)
			(layer "F.SilkS")
			(effects
				(font
					(size 0.7 0.7)
					(thickness 0.15)
				)
				(justify left bottom)
			)
		)
		(property "Value" "R_330R_0402"
			(at -1.011843 1.772047 0)
			(layer "F.Fab")
			(effects
				(font
					(size 0.7 0.7)
					(thickness 0.15)
				)
				(justify left bottom)
			)
		)
		(property "Datasheet" "https://www.bourns.com/docs/product-datasheets/cr.pdf"
			(at 0 0 0)
			(layer "F.Fab")
			(hide yes)
			(effects
				(font
					(size 1.27 1.27)
					(thickness 0.15)
				)
			)
		)
		(property "Description" "SMD Chip Resistor, 330 ohm, ± 1%, 62.5 mW, 0402 [1005 Metric], Thick Film, General Purpose"
			(at 0 0 0)
			(layer "F.Fab")
			(hide yes)
			(effects
				(font
					(size 1.27 1.27)
					(thickness 0.15)
				)
			)
		)
		(property "MPN" "CR0402-FX-3300GLF"
			(at 0 0 0)
			(unlocked yes)
			(layer "F.Fab")
			(hide yes)
			(effects
				(font
					(size 1 1)
					(thickness 0.15)
				)
			)
		)
		(property "Manufacturer" "Bourns"
			(at 0 0 0)
			(unlocked yes)
			(layer "F.Fab")
			(hide yes)
			(effects
				(font
					(size 1 1)
					(thickness 0.15)
				)
			)
		)
		(property "License" "Apache-2.0"
			(at 0 0 0)
			(unlocked yes)
			(layer "F.Fab")
			(hide yes)
			(effects
				(font
					(size 1 1)
					(thickness 0.15)
				)
			)
		)
		(property "Author" "Antmicro"
			(at 0 0 0)
			(unlocked yes)
			(layer "F.Fab")
			(hide yes)
			(effects
				(font
					(size 1 1)
					(thickness 0.15)
				)
			)
		)
		(property "Val" "330R"
			(at 0 0 0)
			(unlocked yes)
			(layer "F.Fab")
			(hide yes)
			(effects
				(font
					(size 1 1)
					(thickness 0.15)
				)
			)
		)
		(property "Tolerance" "1%"
			(at 0 0 0)
			(unlocked yes)
			(layer "F.Fab")
			(hide yes)
			(effects
				(font
					(size 1 1)
					(thickness 0.15)
				)
			)
		)
		(sheetname "/X710 DCDC converters/")
		(sheetfile "DCDC_converters_X710.kicad_sch")
		(attr smd)
		(fp_rect
			(start -0.925 -0.47)
			(end 0.925 0.47)
			(stroke
				(width 0.05)
				(type default)
			)
			(fill no)
			(layer "F.CrtYd")
		)
		(fp_rect
			(start -0.5 -0.25)
			(end 0.5 0.25)
			(stroke
				(width 0.15)
				(type solid)
			)
			(fill no)
			(layer "F.Fab")
		)
		(fp_text user "${REFERENCE}"
			(at -0.95 3.168 0)
			(layer "F.Fab")
			(effects
				(font
					(size 0.7 0.7)
					(thickness 0.15)
				)
				(justify left bottom)
			)
		)
		(fp_text user "Author: Antmicro"
			(at -0.95 4.169 0)
			(layer "F.Fab")
			(effects
				(font
					(size 0.7 0.7)
					(thickness 0.15)
				)
				(justify left bottom)
			)
		)
		(fp_text user "License: Apache-2.0"
			(at -0.95 5.169 0)
			(layer "F.Fab")
			(effects
				(font
					(size 0.7 0.7)
					(thickness 0.15)
				)
				(justify left bottom)
			)
		)
		(pad "1" smd roundrect
			(at -0.48 0)
			(size 0.59 0.64)
			(layers "F.Cu" "F.Mask" "F.Paste")
			(roundrect_rratio 0.25)
			(net 419 "Net-(D11-A)")
			(pintype "passive")
		)
		(pad "2" smd roundrect
			(at 0.48 0)
			(size 0.59 0.64)
			(layers "F.Cu" "F.Mask" "F.Paste")
			(roundrect_rratio 0.25)
			(net 334 "/X710 DCDC converters/+3V3_OUT")
			(pintype "passive")
		)
	)
	(footprint "antmicro-footprints:R_0402_1005Metric"
		(layer "F.Cu")
		(at 139 67.549999)
		(descr "Resistor SMD 0402")
		(tags "resistor SMD 0402")
		(property "Reference" "R113"
			(at 1 0.450001 0)
			(layer "F.SilkS")
			(effects
				(font
					(size 0.7 0.7)
					(thickness 0.15)
				)
				(justify left bottom)
			)
		)
		(property "Value" "R_0R_0402"
			(at -1.011843 1.772047 0)
			(layer "F.Fab")
			(effects
				(font
					(size 0.7 0.7)
					(thickness 0.15)
				)
				(justify left bottom)
			)
		)
		(property "Datasheet" "https://industrial.panasonic.com/cdbs/www-data/pdf/RDA0000/AOA0000C301.pdf"
			(at 0 0 0)
			(layer "F.Fab")
			(hide yes)
			(effects
				(font
					(size 1.27 1.27)
					(thickness 0.15)
				)
			)
		)
		(property "Description" "SMD Chip Resistor, Jumper, 0 ohm, 100 mW, 0402 [1005 Metric], Thick Film, General Purpose"
			(at 0 0 0)
			(layer "F.Fab")
			(hide yes)
			(effects
				(font
					(size 1.27 1.27)
					(thickness 0.15)
				)
			)
		)
		(property "MPN" "ERJ2GE0R00X"
			(at 0 0 0)
			(unlocked yes)
			(layer "F.Fab")
			(hide yes)
			(effects
				(font
					(size 1 1)
					(thickness 0.15)
				)
			)
		)
		(property "Manufacturer" "Panasonic"
			(at 0 0 0)
			(unlocked yes)
			(layer "F.Fab")
			(hide yes)
			(effects
				(font
					(size 1 1)
					(thickness 0.15)
				)
			)
		)
		(property "License" "Apache-2.0"
			(at 0 0 0)
			(unlocked yes)
			(layer "F.Fab")
			(hide yes)
			(effects
				(font
					(size 1 1)
					(thickness 0.15)
				)
			)
		)
		(property "Author" "Antmicro"
			(at 0 0 0)
			(unlocked yes)
			(layer "F.Fab")
			(hide yes)
			(effects
				(font
					(size 1 1)
					(thickness 0.15)
				)
			)
		)
		(property "Val" "0R"
			(at 0 0 0)
			(unlocked yes)
			(layer "F.Fab")
			(hide yes)
			(effects
				(font
					(size 1 1)
					(thickness 0.15)
				)
			)
		)
		(property "Tolerance" "~"
			(at 0 0 0)
			(unlocked yes)
			(layer "F.Fab")
			(hide yes)
			(effects
				(font
					(size 1 1)
					(thickness 0.15)
				)
			)
		)
		(property "Current" "1A"
			(at 0 0 0)
			(unlocked yes)
			(layer "F.Fab")
			(hide yes)
			(effects
				(font
					(size 1 1)
					(thickness 0.15)
				)
			)
		)
		(sheetname "/X710-AT2 PCIe/")
		(sheetfile "x710-at2-pcie.kicad_sch")
		(attr smd)
		(fp_rect
			(start -0.925 -0.47)
			(end 0.925 0.47)
			(stroke
				(width 0.05)
				(type default)
			)
			(fill no)
			(layer "F.CrtYd")
		)
		(fp_rect
			(start -0.5 -0.25)
			(end 0.5 0.25)
			(stroke
				(width 0.15)
				(type solid)
			)
			(fill no)
			(layer "F.Fab")
		)
		(fp_text user "Author: Antmicro"
			(at -0.95 4.169 0)
			(layer "F.Fab")
			(effects
				(font
					(size 0.7 0.7)
					(thickness 0.15)
				)
				(justify left bottom)
			)
		)
		(fp_text user "License: Apache-2.0"
			(at -0.95 5.169 0)
			(layer "F.Fab")
			(effects
				(font
					(size 0.7 0.7)
					(thickness 0.15)
				)
				(justify left bottom)
			)
		)
		(fp_text user "${REFERENCE}"
			(at -0.95 3.168 0)
			(layer "F.Fab")
			(effects
				(font
					(size 0.7 0.7)
					(thickness 0.15)
				)
				(justify left bottom)
			)
		)
		(pad "1" smd roundrect
			(at -0.48 0)
			(size 0.59 0.64)
			(layers "F.Cu" "F.Mask" "F.Paste")
			(roundrect_rratio 0.25)
			(net 393 "/TB Controller/REFCLK.+")
			(pintype "passive")
		)
		(pad "2" smd roundrect
			(at 0.48 0)
			(size 0.59 0.64)
			(layers "F.Cu" "F.Mask" "F.Paste")
			(roundrect_rratio 0.25)
			(net 159 "/X710-AT2 PCIe/CLK+")
			(pintype "passive")
		)
	)
)
